# S9S_MB_2U (Grand Teton) — schematic netlist excerpt (pin names and nets, part order shuffled) for the footprints in the layout excerpt that follows; sources: Cadence DE-HDL packaged netlist, KiCad conversion of 03242023_DA0F0TMBIJ0_F0T_Motherboard_J_brd_V01_OCP.brd

J20  SCONN288_ADR50017P087CC  SCONN288_ADR50017-P087CC IO  pkg DDR288S_1-1VXB  page 101
  VIN_BULK0  = P12V_S3_AUX_CPU1_NVDIMM
  RFU0  = TP_CHB_CPU1_DIMM2_FRU_0
  VIN_MGMT  = P3V3_AUX
  HSCL  = I3C_SPD_DDRABCD_CPU1_LVC1_SCL_3
  HSDA  = I3C_SPD_DDRABCD_CPU1_LVC1_SDA
  VSS0  = GND
  DQ0_A  = M_B_CPU1_SA_DQ<0>
  VSS1  = GND
  DQ1_A  = M_B_CPU1_SA_DQ<1>
  VSS2  = GND
  DQS0_A_T  = M_B_CPU1_SA_DQS_DP<0>
  DQS0_A_C  = M_B_CPU1_SA_DQS_DN<0>
  VSS3  = GND
  DQ4_A  = M_B_CPU1_SA_DQ<4>
  VSS4  = GND
  DQ5_A  = M_B_CPU1_SA_DQ<5>
  VSS5  = GND
  DQ8_A  = M_B_CPU1_SA_DQ<8>
  VSS6  = GND
  DQ9_A  = M_B_CPU1_SA_DQ<9>
  VSS7  = GND
  DQS1_A_T  = M_B_CPU1_SA_DQS_DP<1>
  DQS1_A_C  = M_B_CPU1_SA_DQS_DN<1>
  VSS8  = GND
  DQ12_A  = M_B_CPU1_SA_DQ<12>
  VSS9  = GND
  DQ13_A  = M_B_CPU1_SA_DQ<13>
  VSS10  = GND
  DQ16_A  = M_B_CPU1_SA_DQ<16>
  VSS11  = GND
  DQ17_A  = M_B_CPU1_SA_DQ<17>
  VSS12  = GND
  DQS2_A_T  = M_B_CPU1_SA_DQS_DP<2>
  DQS2_A_C  = M_B_CPU1_SA_DQS_DN<2>
  VSS13  = GND
  DQ20_A  = M_B_CPU1_SA_DQ<20>
  VSS14  = GND
  DQ21_A  = M_B_CPU1_SA_DQ<21>
  VSS15  = GND
  DQ24_A  = M_B_CPU1_SA_DQ<24>
  VSS16  = GND
  DQ25_A  = M_B_CPU1_SA_DQ<25>
  VSS17  = GND
  DQS3_A_T  = M_B_CPU1_SA_DQS_DP<3>
  DQS3_A_C  = M_B_CPU1_SA_DQS_DN<3>
  VSS18  = GND
  DQ28_A  = M_B_CPU1_SA_DQ<28>
  VSS19  = GND
  DQ29_A  = M_B_CPU1_SA_DQ<29>
  VSS20  = GND
  CB0_A  = M_B_CPU1_SA_CB<0>
  VSS21  = GND
  CB1_A  = M_B_CPU1_SA_CB<1>
  VSS22  = GND
  DQS4_A_T  = M_B_CPU1_SA_DQS_DP<4>
  DQS4_A_C  = M_B_CPU1_SA_DQS_DN<4>
  VSS23  = GND
  CB4_A  = M_B_CPU1_SA_CB<4>
  VSS24  = GND
  CB5_A  = M_B_CPU1_SA_CB<5>
  VSS25  = GND
  ALERT_N  = M_B_CPU1_ALERT_N
  VSS26  = GND
  CS0_A_N  = M_B_CPU1_SA_CS_N<2>
  VSS27  = GND
  CA0_A  = M_B_CPU1_SA_CA<0>
  VSS28  = GND
  CA2_A  = M_B_CPU1_SA_CA<2>
  VSS29  = GND
  CA4_A  = M_B_CPU1_SA_CA<4>
  VSS30  = GND
  CA6_A  = M_B_CPU1_SA_CA<6>
  VSS31  = GND
  PAR_A  = M_B_CPU1_SA_PAR
  VSS32  = GND
  CA0_B  = M_B_CPU1_SB_CA<0>
  VSS33  = GND
  CA2_B  = M_B_CPU1_SB_CA<2>
  VSS34  = GND
  CA4_B  = M_B_CPU1_SB_CA<4>
  VSS35  = GND
  CA6_B  = M_B_CPU1_SB_CA<6>
  VSS36  = GND
  CS0_B_N  = M_B_CPU1_SB_CS_N<2>
  VSS37  = GND
  \lbd||rsp_a_n\  = M_B_CPU1_SA_RSP<1>
  \lbs||rsp_b_n\  = M_B_CPU1_SB_RSP<1>
  VSS38  = GND
  CB4_B  = M_B_CPU1_SB_CB<4>
  VSS39  = GND
  CB5_B  = M_B_CPU1_SB_CB<5>
  VSS40  = GND
  \dqs9_b_t||tdqs9_b_t||dbi4_b_n\  = M_B_CPU1_SB_DQS_DP<9>
  \dqs9_b_c||tdqs9_b_c\  = M_B_CPU1_SB_DQS_DN<9>
  VSS41  = GND
  CB0_B  = M_B_CPU1_SB_CB<0>
  VSS42  = GND
  CB1_B  = M_B_CPU1_SB_CB<1>
  VSS43  = GND
  DQ0_B  = M_B_CPU1_SB_DQ<0>
  VSS44  = GND
  DQ1_B  = M_B_CPU1_SB_DQ<1>
  VSS45  = GND
  DQS0_B_T  = M_B_CPU1_SB_DQS_DP<0>
  DQS0_B_C  = M_B_CPU1_SB_DQS_DN<0>
  VSS46  = GND
  DQ4_B  = M_B_CPU1_SB_DQ<4>
  VSS47  = GND
  DQ5_B  = M_B_CPU1_SB_DQ<5>
  VSS48  = GND
  DQ8_B  = M_B_CPU1_SB_DQ<8>
  VSS49  = GND
  DQ9_B  = M_B_CPU1_SB_DQ<9>
  VSS50  = GND
  DQS1_B_T  = M_B_CPU1_SB_DQS_DP<1>
  DQS1_B_C  = M_B_CPU1_SB_DQS_DN<1>
  VSS51  = GND
  DQ12_B  = M_B_CPU1_SB_DQ<12>
  VSS52  = GND
  DQ13_B  = M_B_CPU1_SB_DQ<13>
  VSS53  = GND
  DQ16_B  = M_B_CPU1_SB_DQ<16>
  VSS54  = GND
  DQ17_B  = M_B_CPU1_SB_DQ<17>
  VSS55  = GND
  DQS2_B_T  = M_B_CPU1_SB_DQS_DP<2>
  DQS2_B_C  = M_B_CPU1_SB_DQS_DN<2>
  VSS56  = GND
  DQ20_B  = M_B_CPU1_SB_DQ<20>
  VSS57  = GND
  DQ21_B  = M_B_CPU1_SB_DQ<21>
  VSS58  = GND
  DQ24_B  = M_B_CPU1_SB_DQ<24>
  VSS59  = GND
  DQ25_B  = M_B_CPU1_SB_DQ<25>
  VSS60  = GND
  DQS3_B_T  = M_B_CPU1_SB_DQS_DP<3>
  DQS3_B_C  = M_B_CPU1_SB_DQS_DN<3>
  VSS61  = GND
  DQ28_B  = M_B_CPU1_SB_DQ<28>
  VSS62  = GND
  DQ29_B  = M_B_CPU1_SB_DQ<29>
  VSS63  = GND
  RFU1  = TP_CHB_CPU1_DIMM2_FRU_1
  VIN_BULK1  = P12V_S3_AUX_CPU1_NVDIMM
  VIN_BULK2  = P12V_S3_AUX_CPU1_NVDIMM
  \pwr_good||fail_n\  = PWRGD_CHB_CPU1_DIMM2
  HSA  = PD_CHB_CPU1_DIMM2_SAA
  RFU2  = TP_CHB_CPU1_DIMM2_FRU_2
  RFU3  = TP_CHB_CPU1_DIMM2_FRU_3
  VSS64  = GND
  DQ2_A  = M_B_CPU1_SA_DQ<2>
  VSS65  = GND
  DQ3_A  = M_B_CPU1_SA_DQ<3>
  VSS66  = GND
  \dqs5_a_c||tdqs5_a_c||dqs5_a_t||tdqs5_a_t\  = M_B_CPU1_SA_DQS_DN<5>
  \dqs5_a_t||tdqs5_a_t\  = M_B_CPU1_SA_DQS_DP<5>
  VSS67  = GND
  DQ6_A  = M_B_CPU1_SA_DQ<6>
  VSS68  = GND
  DQ7_A  = M_B_CPU1_SA_DQ<7>
  VSS69  = GND
  DQ10_A  = M_B_CPU1_SA_DQ<10>
  VSS70  = GND
  DQ11_A  = M_B_CPU1_SA_DQ<11>
  VSS71  = GND
  \dqs6_a_c||tdqs6_a_c||dqs6_a_t||tdqs6_a_t\  = M_B_CPU1_SA_DQS_DN<6>
  \dqs6_a_t||tdqs6_a_t\  = M_B_CPU1_SA_DQS_DP<6>
  VSS72  = GND
  DQ14_A  = M_B_CPU1_SA_DQ<14>
  VSS73  = GND
  DQ15_A  = M_B_CPU1_SA_DQ<15>
  VSS74  = GND
  DQ18_A  = M_B_CPU1_SA_DQ<18>
  VSS75  = GND
  DQ19_A  = M_B_CPU1_SA_DQ<19>
  VSS76  = GND
  \dqs7_a_c||tdqs7_a_c\  = M_B_CPU1_SA_DQS_DN<7>
  \dqs7_a_t||tdqs7_a_t\  = M_B_CPU1_SA_DQS_DP<7>
  VSS77  = GND
  DQ22_A  = M_B_CPU1_SA_DQ<22>
  VSS78  = GND
  DQ23_A  = M_B_CPU1_SA_DQ<23>
  VSS79  = GND
  DQ26_A  = M_B_CPU1_SA_DQ<26>
  VSS80  = GND
  DQ27_A  = M_B_CPU1_SA_DQ<27>
  VSS81  = GND
  \dqs8_a_c||tdqs8_a_c\  = M_B_CPU1_SA_DQS_DN<8>
  \dqs8_a_t||tdqs8_a_t\  = M_B_CPU1_SA_DQS_DP<8>
  VSS82  = GND
  DQ30_A  = M_B_CPU1_SA_DQ<30>
  VSS83  = GND
  DQ31_A  = M_B_CPU1_SA_DQ<31>
  VSS84  = GND
  CB2_A  = M_B_CPU1_SA_CB<2>
  VSS85  = GND
  CB3_A  = M_B_CPU1_SA_CB<3>
  VSS86  = GND
  \dqs9_a_c||tdqs9_a_c\  = M_B_CPU1_SA_DQS_DN<9>
  \dqs9_a_t||tdqs9_a_t\  = M_B_CPU1_SA_DQS_DP<9>
  VSS87  = GND
  CB6_A  = M_B_CPU1_SA_CB<6>
  VSS88  = GND
  CB7_A  = M_B_CPU1_SA_CB<7>
  VSS89  = GND
  RESET_N  = RST_M_AB_CPU1_FPGA_N
  VSS90  = GND
  CS1_A_N  = M_B_CPU1_SA_CS_N<3>
  VSS91  = GND
  CA1_A  = M_B_CPU1_SA_CA<1>
  VSS92  = GND
  CA3_A  = M_B_CPU1_SA_CA<3>
  VSS93  = GND
  CA5_A  = M_B_CPU1_SA_CA<5>
  VSS94  = GND
  CK_T  = M_B_CPU1_CLK_DP<1>
  CK_C  = M_B_CPU1_CLK_DN<1>
  VSS95  = GND
  RFU4  = TP_CHB_CPU1_DIMM2_FRU_4
  CA1_B  = M_B_CPU1_SB_CA<1>
  VSS96  = GND
  CA3_B  = M_B_CPU1_SB_CA<3>
  VSS97  = GND
  CA5_B  = M_B_CPU1_SB_CA<5>
  VSS98  = GND
  PAR_B  = M_B_CPU1_SB_PAR
  VSS99  = GND
  CS1_B_N  = M_B_CPU1_SB_CS_N<3>
  VSS100  = GND
  RFU5  = TP_CHB_CPU1_DIMM2_FRU_5
  RFU6  = TP_CHB_CPU1_DIMM2_FRU_6
  VSS101  = GND
  CB6_B  = M_B_CPU1_SB_CB<6>
  VSS102  = GND
  CB7_B  = M_B_CPU1_SB_CB<7>
  VSS103  = GND
  DQS4_B_C  = M_B_CPU1_SB_DQS_DN<4>
  DQS4_B_T  = M_B_CPU1_SB_DQS_DP<4>
  VSS104  = GND
  CB2_B  = M_B_CPU1_SB_CB<2>
  VSS105  = GND
  CB3_B  = M_B_CPU1_SB_CB<3>
  VSS106  = GND
  DQ2_B  = M_B_CPU1_SB_DQ<2>
  VSS107  = GND
  DQ3_B  = M_B_CPU1_SB_DQ<3>
  VSS108  = GND
  \dqs5_b_c||tdqs5_b_c\  = M_B_CPU1_SB_DQS_DN<5>
  \dqs5_b_t||tdqs5_b_t\  = M_B_CPU1_SB_DQS_DP<5>
  VSS109  = GND
  DQ6_B  = M_B_CPU1_SB_DQ<6>
  VSS110  = GND
  DQ7_B  = M_B_CPU1_SB_DQ<7>
  VSS111  = GND
  DQ10_B  = M_B_CPU1_SB_DQ<10>
  VSS112  = GND
  DQ11_B  = M_B_CPU1_SB_DQ<11>
  VSS113  = GND
  \dqs6_b_c||tdqs6_b_c\  = M_B_CPU1_SB_DQS_DN<6>
  \dqs6_b_t||tdqs6_b_t\  = M_B_CPU1_SB_DQS_DP<6>
  VSS114  = GND
  DQ14_B  = M_B_CPU1_SB_DQ<14>
  VSS115  = GND
  DQ15_B  = M_B_CPU1_SB_DQ<15>
  VSS116  = GND
  DQ18_B  = M_B_CPU1_SB_DQ<18>
  VSS117  = GND
  DQ19_B  = M_B_CPU1_SB_DQ<19>
  VSS118  = GND
  \dqs7_b_c||tdqs7_b_c\  = M_B_CPU1_SB_DQS_DN<7>
  \dqs7_b_t||tdqs7_b_t\  = M_B_CPU1_SB_DQS_DP<7>
  VSS119  = GND
  DQ22_B  = M_B_CPU1_SB_DQ<22>
  VSS120  = GND
  DQ23_B  = M_B_CPU1_SB_DQ<23>
  VSS121  = GND
  DQ26_B  = M_B_CPU1_SB_DQ<26>
  VSS122  = GND
  DQ27_B  = M_B_CPU1_SB_DQ<27>
  VSS123  = GND
  \dqs8_b_c||tdqs8_b_c\  = M_B_CPU1_SB_DQS_DN<8>
  \dqs8_b_t||tdqs8_b_t\  = M_B_CPU1_SB_DQS_DP<8>
  VSS124  = GND
  DQ30_B  = M_B_CPU1_SB_DQ<30>
  VSS125  = GND
  DQ31_B  = M_B_CPU1_SB_DQ<31>
  VSS126  = GND
  G1  = GND
  G2  = GND
  G3  = GND

(kicad_pcb
	(version 20260206)
	(generator "pcbnew")
	(generator_version "10.0")
	(general
		(thickness 1.6)
		(legacy_teardrops no)
	)
	(paper "A4")
	(title_block
		(title "03242023_DA0F0TMBIJ0_F0T_Motherboard_J_brd_V01_OCP.brd")
		(comment 1 "Grand Teton / footprint 1508 of 6105 (J20), pads 1-45 of 291")
	)
	(layers
		(0 "F.Cu" signal "TOP")
		(4 "In1.Cu" signal "GND")
		(6 "In2.Cu" signal "IN1")
		(8 "In3.Cu" signal "GND1")
		(10 "In4.Cu" signal "IN2")
		(12 "In5.Cu" signal "GND2")
		(14 "In6.Cu" signal "IN3")
		(16 "In7.Cu" signal "GND3")
		(18 "In8.Cu" signal "VCC")
		(20 "In9.Cu" signal "VCC1")
		(22 "In10.Cu" signal "GND4")
		(24 "In11.Cu" signal "IN4")
		(26 "In12.Cu" signal "GND5")
		(28 "In13.Cu" signal "IN5")
		(30 "In14.Cu" signal "GND6")
		(32 "In15.Cu" signal "IN6")
		(34 "In16.Cu" signal "GND7")
		(2 "B.Cu" signal "BOTTOM")
		(9 "F.Adhes" user "F.Adhesive")
		(11 "B.Adhes" user "B.Adhesive")
		(13 "F.Paste" user "Package Geometry/Pastemask Top")
		(15 "B.Paste" user "Package Geometry/Pastemask Bottom")
		(5 "F.SilkS" user "Ref Des/Silkscreen Top")
		(7 "B.SilkS" user "Ref Des/Silkscreen Bottom")
		(1 "F.Mask" user "Board Geometry/Soldermask Top")
		(3 "B.Mask" user "Board Geometry/Soldermask Bottom")
		(17 "Dwgs.User" user "User.Drawings")
		(19 "Cmts.User" user "User.Comments")
		(21 "Eco1.User" user "User.Eco1")
		(23 "Eco2.User" user "User.Eco2")
		(25 "Edge.Cuts" user "Board Geometry/Outline")
		(27 "Margin" user)
		(31 "F.CrtYd" user "Package Geometry/Place Bound Top")
		(29 "B.CrtYd" user "Package Geometry/Place Bound Bottom")
		(35 "F.Fab" user "Ref Des/Assembly Top")
		(33 "B.Fab" user "Ref Des/Assembly Bottom")
	)
	(footprint ""
		(layer "F.Cu")
		(at 47.90948 -258.091686)
		(property "Reference" "J20"
			(at -2.74066 -81.678272 0)
			(unlocked yes)
			(layer "F.SilkS")
			(effects
				(font
					(size 0.7874 0.5842)
					(thickness 0.1524)
				)
				(justify left)
			)
		)
		(property "Value" ""
			(at 0 0 0)
			(layer "F.Fab")
			(effects
				(font
					(size 1.27 1.27)
				)
			)
		)
		(duplicate_pad_numbers_are_jumpers no)
		(pad "1" smd rect
			(at -2.050034 -63.324994 270)
			(size 0.519938 1.4986)
			(layers "F.Cu" "F.Mask" "F.Paste")
			(net "P12V_S3_AUX_CPU1_NVDIMM")
		)
		(pad "2" smd rect
			(at -2.050034 -62.47511 270)
			(size 0.519938 1.4986)
			(layers "F.Cu" "F.Mask" "F.Paste")
			(net "TP_CHB_CPU1_DIMM2_FRU_0")
		)
		(pad "3" smd rect
			(at -2.050034 -61.624972 270)
			(size 0.519938 1.4986)
			(layers "F.Cu" "F.Mask" "F.Paste")
			(net "P3V3_AUX")
		)
		(pad "4" smd rect
			(at -2.050034 -60.775088 270)
			(size 0.519938 1.4986)
			(layers "F.Cu" "F.Mask" "F.Paste")
			(net "I3C_SPD_DDRABCD_CPU1_LVC1_SCL_3")
		)
		(pad "5" smd rect
			(at -2.050034 -59.92495 270)
			(size 0.519938 1.4986)
			(layers "F.Cu" "F.Mask" "F.Paste")
			(net "I3C_SPD_DDRABCD_CPU1_LVC1_SDA")
		)
		(pad "6" smd rect
			(at -2.050034 -59.075066 270)
			(size 0.519938 1.4986)
			(layers "F.Cu" "F.Mask" "F.Paste")
			(net "GND")
		)
		(pad "7" smd rect
			(at -2.050034 -58.224928 270)
			(size 0.519938 1.4986)
			(layers "F.Cu" "F.Mask" "F.Paste")
			(net "M_B_CPU1_SA_DQ<0>")
		)
		(pad "8" smd rect
			(at -2.050034 -57.375044 270)
			(size 0.519938 1.4986)
			(layers "F.Cu" "F.Mask" "F.Paste")
			(net "GND")
		)
		(pad "9" smd rect
			(at -2.050034 -56.524906 270)
			(size 0.519938 1.4986)
			(layers "F.Cu" "F.Mask" "F.Paste")
			(net "M_B_CPU1_SA_DQ<1>")
		)
		(pad "10" smd rect
			(at -2.050034 -55.675022 270)
			(size 0.519938 1.4986)
			(layers "F.Cu" "F.Mask" "F.Paste")
			(net "GND")
		)
		(pad "11" smd rect
			(at -2.050034 -54.824884 270)
			(size 0.519938 1.4986)
			(layers "F.Cu" "F.Mask" "F.Paste")
			(net "M_B_CPU1_SA_DQS_DP<0>")
		)
		(pad "12" smd rect
			(at -2.050034 -53.975 270)
			(size 0.519938 1.4986)
			(layers "F.Cu" "F.Mask" "F.Paste")
			(net "M_B_CPU1_SA_DQS_DN<0>")
		)
		(pad "13" smd rect
			(at -2.050034 -53.125116 270)
			(size 0.519938 1.4986)
			(layers "F.Cu" "F.Mask" "F.Paste")
			(net "GND")
		)
		(pad "14" smd rect
			(at -2.050034 -52.274978 270)
			(size 0.519938 1.4986)
			(layers "F.Cu" "F.Mask" "F.Paste")
			(net "M_B_CPU1_SA_DQ<4>")
		)
		(pad "15" smd rect
			(at -2.050034 -51.425094 270)
			(size 0.519938 1.4986)
			(layers "F.Cu" "F.Mask" "F.Paste")
			(net "GND")
		)
		(pad "16" smd rect
			(at -2.050034 -50.574956 270)
			(size 0.519938 1.4986)
			(layers "F.Cu" "F.Mask" "F.Paste")
			(net "M_B_CPU1_SA_DQ<5>")
		)
		(pad "17" smd rect
			(at -2.050034 -49.725072 270)
			(size 0.519938 1.4986)
			(layers "F.Cu" "F.Mask" "F.Paste")
			(net "GND")
		)
		(pad "18" smd rect
			(at -2.050034 -48.874934 270)
			(size 0.519938 1.4986)
			(layers "F.Cu" "F.Mask" "F.Paste")
			(net "M_B_CPU1_SA_DQ<8>")
		)
		(pad "19" smd rect
			(at -2.050034 -48.02505 270)
			(size 0.519938 1.4986)
			(layers "F.Cu" "F.Mask" "F.Paste")
			(net "GND")
		)
		(pad "20" smd rect
			(at -2.050034 -47.174912 270)
			(size 0.519938 1.4986)
			(layers "F.Cu" "F.Mask" "F.Paste")
			(net "M_B_CPU1_SA_DQ<9>")
		)
		(pad "21" smd rect
			(at -2.050034 -46.325028 270)
			(size 0.519938 1.4986)
			(layers "F.Cu" "F.Mask" "F.Paste")
			(net "GND")
		)
		(pad "22" smd rect
			(at -2.050034 -45.47489 270)
			(size 0.519938 1.4986)
			(layers "F.Cu" "F.Mask" "F.Paste")
			(net "M_B_CPU1_SA_DQS_DP<1>")
		)
		(pad "23" smd rect
			(at -2.050034 -44.625006 270)
			(size 0.519938 1.4986)
			(layers "F.Cu" "F.Mask" "F.Paste")
			(net "M_B_CPU1_SA_DQS_DN<1>")
		)
		(pad "24" smd rect
			(at -2.050034 -43.775122 270)
			(size 0.519938 1.4986)
			(layers "F.Cu" "F.Mask" "F.Paste")
			(net "GND")
		)
		(pad "25" smd rect
			(at -2.050034 -42.924984 270)
			(size 0.519938 1.4986)
			(layers "F.Cu" "F.Mask" "F.Paste")
			(net "M_B_CPU1_SA_DQ<12>")
		)
		(pad "26" smd rect
			(at -2.050034 -42.0751 270)
			(size 0.519938 1.4986)
			(layers "F.Cu" "F.Mask" "F.Paste")
			(net "GND")
		)
		(pad "27" smd rect
			(at -2.050034 -41.224962 270)
			(size 0.519938 1.4986)
			(layers "F.Cu" "F.Mask" "F.Paste")
			(net "M_B_CPU1_SA_DQ<13>")
		)
		(pad "28" smd rect
			(at -2.050034 -40.375078 270)
			(size 0.519938 1.4986)
			(layers "F.Cu" "F.Mask" "F.Paste")
			(net "GND")
		)
		(pad "29" smd rect
			(at -2.050034 -39.52494 270)
			(size 0.519938 1.4986)
			(layers "F.Cu" "F.Mask" "F.Paste")
			(net "M_B_CPU1_SA_DQ<16>")
		)
		(pad "30" smd rect
			(at -2.050034 -38.675056 270)
			(size 0.519938 1.4986)
			(layers "F.Cu" "F.Mask" "F.Paste")
			(net "GND")
		)
		(pad "31" smd rect
			(at -2.050034 -37.824918 270)
			(size 0.519938 1.4986)
			(layers "F.Cu" "F.Mask" "F.Paste")
			(net "M_B_CPU1_SA_DQ<17>")
		)
		(pad "32" smd rect
			(at -2.050034 -36.975034 270)
			(size 0.519938 1.4986)
			(layers "F.Cu" "F.Mask" "F.Paste")
			(net "GND")
		)
		(pad "33" smd rect
			(at -2.050034 -36.124896 270)
			(size 0.519938 1.4986)
			(layers "F.Cu" "F.Mask" "F.Paste")
			(net "M_B_CPU1_SA_DQS_DP<2>")
		)
		(pad "34" smd rect
			(at -2.050034 -35.275012 270)
			(size 0.519938 1.4986)
			(layers "F.Cu" "F.Mask" "F.Paste")
			(net "M_B_CPU1_SA_DQS_DN<2>")
		)
		(pad "35" smd rect
			(at -2.050034 -34.425128 270)
			(size 0.519938 1.4986)
			(layers "F.Cu" "F.Mask" "F.Paste")
			(net "GND")
		)
		(pad "36" smd rect
			(at -2.050034 -33.57499 270)
			(size 0.519938 1.4986)
			(layers "F.Cu" "F.Mask" "F.Paste")
			(net "M_B_CPU1_SA_DQ<20>")
		)
		(pad "37" smd rect
			(at -2.050034 -32.725106 270)
			(size 0.519938 1.4986)
			(layers "F.Cu" "F.Mask" "F.Paste")
			(net "GND")
		)
		(pad "38" smd rect
			(at -2.050034 -31.874968 270)
			(size 0.519938 1.4986)
			(layers "F.Cu" "F.Mask" "F.Paste")
			(net "M_B_CPU1_SA_DQ<21>")
		)
		(pad "39" smd rect
			(at -2.050034 -31.025084 270)
			(size 0.519938 1.4986)
			(layers "F.Cu" "F.Mask" "F.Paste")
			(net "GND")
		)
		(pad "40" smd rect
			(at -2.050034 -30.174946 270)
			(size 0.519938 1.4986)
			(layers "F.Cu" "F.Mask" "F.Paste")
			(net "M_B_CPU1_SA_DQ<24>")
		)
		(pad "41" smd rect
			(at -2.050034 -29.325062 270)
			(size 0.519938 1.4986)
			(layers "F.Cu" "F.Mask" "F.Paste")
			(net "GND")
		)
		(pad "42" smd rect
			(at -2.050034 -28.474924 270)
			(size 0.519938 1.4986)
			(layers "F.Cu" "F.Mask" "F.Paste")
			(net "M_B_CPU1_SA_DQ<25>")
		)
		(pad "43" smd rect
			(at -2.050034 -27.62504 270)
			(size 0.519938 1.4986)
			(layers "F.Cu" "F.Mask" "F.Paste")
			(net "GND")
		)
		(pad "44" smd rect
			(at -2.050034 -26.774902 270)
			(size 0.519938 1.4986)
			(layers "F.Cu" "F.Mask" "F.Paste")
			(net "M_B_CPU1_SA_DQS_DP<3>")
		)
		(pad "45" smd rect
			(at -2.050034 -25.925018 270)
			(size 0.519938 1.4986)
			(layers "F.Cu" "F.Mask" "F.Paste")
			(net "M_B_CPU1_SA_DQS_DN<3>")
		)
	)
)
